# Stackup_F0T_Management_Board_12L_1p6mm_IT-170GRA1_RG311_Rev0p2_20220715 的複本.xls — Vendor Stackup (pcb-stackup)
| STACKUP |  |  |  | Target Z (ohms) - MicroStrip |  |  |  |  |  |  |  | 50 |  |  | Breakout | 85 |  |  |  |  | 100 |  |  |  |  | Breakout |  |
|  |  |  |  | Target Z (ohms) - StripLine |  |  |  |  |  |  |  | 50 |  |  |  | 85 |  |  |  |  | 100 |  |  |  |  |  |  |
|  |  |  |  | Z tolerance |  |  |  |  |  |  |  | 0.1 |  |  |  | 0.1 |  |  |  |  | 0.1 |  |  |  |  |  |  |
|  |  |  |  | Z Type |  |  |  |  |  |  |  | Single |  |  | Single | Differential |  |  |  |  | Differential |  |  |  |  | Differential |  |
| Layer# | Material | Description |  | Copper Weight (oz) | Thickness (mil) | Tolerance (mil) | Glass Fabric | Er | Vendor Thickness (mil) | Vendor Glass Fabric | Vendor Er | Width | Vendor Width | Vendor Impedance | Width | Width | Space | Vendor Width | Vendor Space | Vendor Impedance | Width | Space | Vendor Width | Vendor Space | Vendor Impedance | Width | Space |
|  |  |  | Soldermask |  | 0.6 |  |  | 3.8 |  |  |  |  |  |  |  |  |  |  |  |  |  |  |  |  |  |  |  |
| 1 |  |  | TOP | 0.5+plating | 1.95 |  |  |  |  |  |  | 4.6 |  |  | 3.29 | 5.6 | 8.9 |  |  |  | 4 | 11 |  |  |  | 3.39 | 4 |
|  | IT-170GRA1 |  | PP |  | 2.7 | ±0.709 | 1080x1 | 3.65 |  |  |  |  |  |  |  |  |  |  |  |  |  |  |  |  |  |  |  |
| 2 |  |  | GND | 0.5 (RG311) | 0.65 |  |  |  |  |  |  |  |  |  |  |  |  |  |  |  |  |  |  |  |  |  |  |
|  | IT-170GRA1 |  | CORE |  | 3 | ±0.709 | 1086x1 | 3.65 |  |  |  |  |  |  |  |  |  |  |  |  |  |  |  |  |  |  |  |
| 3 |  |  | IN1 | 0.5 (RG311) | 0.65 |  |  |  |  |  |  | 3.3 |  |  | 3.29 | 4.5 | 8.7 |  |  |  | 3.4 | 13.2 |  |  |  | 3.39 | 4 |
|  | IT-170GRA1 |  | PP |  | 4.5 | ±0.709 | 2116x1 | 3.67 |  |  |  |  |  |  |  |  |  |  |  |  |  |  |  |  |  |  |  |
| 4 |  |  | GND1 | 0.5 (RG311) | 0.65 |  |  |  |  |  |  |  |  |  |  |  |  |  |  |  |  |  |  |  |  |  |  |
|  | IT-170GRA1 |  | CORE |  | 3 | ±0.709 | 1086x1 | 3.65 |  |  |  |  |  |  |  |  |  |  |  |  |  |  |  |  |  |  |  |
| 5 |  |  | IN2 | 0.5 (RG311) | 0.65 |  |  |  |  |  |  | 4.2 |  |  | 3.29 | 5.4 | 8.6 |  |  |  | 4 | 9.6 |  |  |  | 3.39 | 4 |
|  | IT-170GRA1 |  | PP |  | 9.35 | ±1.5 | 2116x2 | 3.71 |  |  |  |  |  |  |  |  |  |  |  |  |  |  |  |  |  |  |  |
| 6 |  |  | VCC | 1 (RG311) | 1.3 |  |  |  |  |  |  |  |  |  |  |  |  |  |  |  |  |  |  |  |  |  |  |
|  | IT-170GRA1 |  | CORE |  | 5 | ±0.984 | 2116x1 | 3.67 |  |  |  |  |  |  |  |  |  |  |  |  |  |  |  |  |  |  |  |
| 7 |  |  | VCC1 | 1 (RG311) | 1.3 |  |  |  |  |  |  |  |  |  |  |  |  |  |  |  |  |  |  |  |  |  |  |
|  | IT-170GRA1 |  | PP |  | 9.35 | ±1.5 | 2116x2 | 3.71 |  |  |  |  |  |  |  |  |  |  |  |  |  |  |  |  |  |  |  |
| 8 |  |  | IN3 | 0.5 (RG311) | 0.65 |  |  |  |  |  |  | 4.2 |  |  | 3.29 | 5.4 | 8.6 |  |  |  | 4 | 9.6 |  |  |  | 3.39 | 4 |
|  | IT-170GRA1 |  | CORE |  | 3 | ±0.709 | 1086x1 | 3.65 |  |  |  |  |  |  |  |  |  |  |  |  |  |  |  |  |  |  |  |
| 9 |  |  | GND2 | 0.5 (RG311) | 0.65 |  |  |  |  |  |  |  |  |  |  |  |  |  |  |  |  |  |  |  |  |  |  |
|  | IT-170GRA1 |  | PP |  | 4.5 | ±0.709 | 2116x1 | 3.67 |  |  |  |  |  |  |  |  |  |  |  |  |  |  |  |  |  |  |  |
| 10 |  |  | IN4 | 0.5 (RG311) | 0.65 |  |  |  |  |  |  | 3.3 |  |  | 3.29 | 4.5 | 8.7 |  |  |  | 3.4 | 13.2 |  |  |  | 3.39 | 4 |
|  | IT-170GRA1 |  | CORE |  | 3 | ±0.709 | 1086x1 | 3.65 |  |  |  |  |  |  |  |  |  |  |  |  |  |  |  |  |  |  |  |
| 11 |  |  | GND3 | 0.5 (RG311) | 0.65 |  |  |  |  |  |  |  |  |  |  |  |  |  |  |  |  |  |  |  |  |  |  |
|  | IT-170GRA1 |  | PP |  | 2.7 | ±0.709 | 1080x1 | 3.65 |  |  |  |  |  |  |  |  |  |  |  |  |  |  |  |  |  |  |  |
| 12 |  |  | BOTTOM | 0.5+plating | 1.95 |  |  |  |  |  |  | 4.6 |  |  | 3.29 | 5.6 | 8.9 |  |  |  | 4 | 11 |  |  |  | 3.39 | 4 |
|  |  |  | Soldermask |  | 0.6 |  |  | 3.8 |  |  |  |  |  |  |  |  |  |  |  |  |  |  |  |  |  |  |  |
|  |  |  |  | Total | 63 | ±10% |  |  | 0 |  |  |  |  |  |  |  |  |  |  |  |  |  |  |  |  |  |  |
